(kicad_pcb
	(version 20260206)
	(generator "pcbnew")
	(generator_version "10.0")
	(general
		(thickness 1.6)
		(legacy_teardrops no)
	)
	(paper "A4")
	(title_block
		(title "01162023_DA0F0TEBIF0_F0T_Expander_BD_F_brd_V02_OCP.brd")
		(comment 1 "Grand Teton / footprints 9105-9113 of 9728")
	)
	(layers
		(0 "F.Cu" signal "TOP")
		(4 "In1.Cu" signal "GND")
		(6 "In2.Cu" signal "VCC")
		(8 "In3.Cu" signal "VCC1")
		(10 "In4.Cu" signal "GND1")
		(12 "In5.Cu" signal "IN1")
		(14 "In6.Cu" signal "GND2")
		(16 "In7.Cu" signal "IN2")
		(18 "In8.Cu" signal "GND3")
		(20 "In9.Cu" signal "IN3")
		(22 "In10.Cu" signal "GND4")
		(24 "In11.Cu" signal "IN4")
		(26 "In12.Cu" signal "GND5")
		(28 "In13.Cu" signal "IN5")
		(30 "In14.Cu" signal "GND6")
		(32 "In15.Cu" signal "IN6")
		(34 "In16.Cu" signal "GND7")
		(2 "B.Cu" signal "BOTTOM")
		(9 "F.Adhes" user "F.Adhesive")
		(11 "B.Adhes" user "B.Adhesive")
		(13 "F.Paste" user "Package Geometry/Pastemask Top")
		(15 "B.Paste" user "Package Geometry/Pastemask Bottom")
		(5 "F.SilkS" user "Ref Des/Silkscreen Top")
		(7 "B.SilkS" user "Ref Des/Silkscreen Bottom")
		(1 "F.Mask" user "Board Geometry/Soldermask Top")
		(3 "B.Mask" user "Board Geometry/Soldermask Bottom")
		(17 "Dwgs.User" user "User.Drawings")
		(19 "Cmts.User" user "User.Comments")
		(21 "Eco1.User" user "User.Eco1")
		(23 "Eco2.User" user "User.Eco2")
		(25 "Edge.Cuts" user "Board Geometry/Outline")
		(27 "Margin" user)
		(31 "F.CrtYd" user "Package Geometry/Place Bound Top")
		(29 "B.CrtYd" user "Package Geometry/Place Bound Bottom")
		(35 "F.Fab" user "Ref Des/Assembly Top")
		(33 "B.Fab" user "Ref Des/Assembly Bottom")
	)
	(footprint ""
		(layer "B.Cu")
		(at 141.268196 -200.51141 90)
		(property "Reference" "C2594"
			(at 0 0 90)
			(layer "B.SilkS")
			(hide yes)
			(effects
				(font
					(size 1.27 1.27)
				)
				(justify mirror)
			)
		)
		(property "Value" ""
			(at 0 0 90)
			(layer "B.Fab")
			(effects
				(font
					(size 1.27 1.27)
				)
				(justify mirror)
			)
		)
		(duplicate_pad_numbers_are_jumpers no)
		(fp_line
			(start 0.7874 -0.4064)
			(end -0.7874 -0.4064)
			(stroke
				(width 0.1524)
				(type default)
			)
			(layer "B.SilkS")
		)
		(fp_line
			(start -0.7874 -0.4064)
			(end -0.7874 0.4064)
			(stroke
				(width 0.1524)
				(type default)
			)
			(layer "B.SilkS")
		)
		(fp_line
			(start 0.7874 0.4064)
			(end 0.7874 -0.4064)
			(stroke
				(width 0.1524)
				(type default)
			)
			(layer "B.SilkS")
		)
		(fp_line
			(start -0.7874 0.4064)
			(end 0.7874 0.4064)
			(stroke
				(width 0.1524)
				(type default)
			)
			(layer "B.SilkS")
		)
		(fp_line
			(start 0.67945 -0.305054)
			(end 0.12065 -0.305054)
			(stroke
				(width 0.1)
				(type default)
			)
			(layer "B.Fab")
		)
		(fp_line
			(start 0.12065 -0.305054)
			(end 0.12065 -0.2794)
			(stroke
				(width 0.1)
				(type default)
			)
			(layer "B.Fab")
		)
		(fp_line
			(start -0.12065 -0.3048)
			(end -0.67945 -0.3048)
			(stroke
				(width 0.1)
				(type default)
			)
			(layer "B.Fab")
		)
		(fp_line
			(start -0.67945 -0.3048)
			(end -0.67945 0.3048)
			(stroke
				(width 0.1)
				(type default)
			)
			(layer "B.Fab")
		)
		(fp_line
			(start 0.12065 -0.2794)
			(end -0.12065 -0.2794)
			(stroke
				(width 0.1)
				(type default)
			)
			(layer "B.Fab")
		)
		(fp_line
			(start -0.12065 -0.2794)
			(end -0.12065 -0.3048)
			(stroke
				(width 0.1)
				(type default)
			)
			(layer "B.Fab")
		)
		(fp_line
			(start 0.12065 0.2794)
			(end 0.12065 0.3048)
			(stroke
				(width 0.1)
				(type default)
			)
			(layer "B.Fab")
		)
		(fp_line
			(start -0.120396 0.2794)
			(end 0.12065 0.2794)
			(stroke
				(width 0.1)
				(type default)
			)
			(layer "B.Fab")
		)
		(fp_line
			(start 0.67945 0.3048)
			(end 0.67945 -0.305054)
			(stroke
				(width 0.1)
				(type default)
			)
			(layer "B.Fab")
		)
		(fp_line
			(start 0.12065 0.3048)
			(end 0.67945 0.3048)
			(stroke
				(width 0.1)
				(type default)
			)
			(layer "B.Fab")
		)
		(fp_line
			(start -0.120396 0.3048)
			(end -0.120396 0.2794)
			(stroke
				(width 0.1)
				(type default)
			)
			(layer "B.Fab")
		)
		(fp_line
			(start -0.67945 0.3048)
			(end -0.120396 0.3048)
			(stroke
				(width 0.1)
				(type default)
			)
			(layer "B.Fab")
		)
		(pad "1" smd circle
			(at 0.40005 0 270)
			(size 0 0)
			(layers "B.Cu" "B.Mask" "B.Paste")
			(net "P1V8_CLI_VCORE")
		)
		(pad "2" smd circle
			(at -0.40005 0 270)
			(size 0 0)
			(layers "B.Cu" "B.Mask" "B.Paste")
			(net "GND")
		)
	)
	(footprint ""
		(layer "B.Cu")
		(at 70.104 -97.663)
		(property "Reference" "R55"
			(at 0 0 0)
			(layer "B.SilkS")
			(hide yes)
			(effects
				(font
					(size 1.27 1.27)
				)
				(justify mirror)
			)
		)
		(property "Value" ""
			(at 0 0 0)
			(layer "B.Fab")
			(effects
				(font
					(size 1.27 1.27)
				)
				(justify mirror)
			)
		)
		(duplicate_pad_numbers_are_jumpers no)
		(fp_line
			(start -0.7874 -0.4064)
			(end -0.7874 0.4064)
			(stroke
				(width 0.1524)
				(type default)
			)
			(layer "B.SilkS")
		)
		(fp_line
			(start -0.7874 0.4064)
			(end 0.7874 0.4064)
			(stroke
				(width 0.1524)
				(type default)
			)
			(layer "B.SilkS")
		)
		(fp_line
			(start 0.7874 -0.4064)
			(end -0.7874 -0.4064)
			(stroke
				(width 0.1524)
				(type default)
			)
			(layer "B.SilkS")
		)
		(fp_line
			(start 0.7874 0.4064)
			(end 0.7874 -0.4064)
			(stroke
				(width 0.1524)
				(type default)
			)
			(layer "B.SilkS")
		)
		(fp_line
			(start -0.67945 -0.3048)
			(end -0.67945 0.3048)
			(stroke
				(width 0.1)
				(type default)
			)
			(layer "B.Fab")
		)
		(fp_line
			(start -0.67945 0.3048)
			(end -0.120396 0.3048)
			(stroke
				(width 0.1)
				(type default)
			)
			(layer "B.Fab")
		)
		(fp_line
			(start -0.12065 -0.3048)
			(end -0.67945 -0.3048)
			(stroke
				(width 0.1)
				(type default)
			)
			(layer "B.Fab")
		)
		(fp_line
			(start -0.12065 -0.2794)
			(end -0.12065 -0.3048)
			(stroke
				(width 0.1)
				(type default)
			)
			(layer "B.Fab")
		)
		(fp_line
			(start -0.120396 0.2794)
			(end 0.12065 0.2794)
			(stroke
				(width 0.1)
				(type default)
			)
			(layer "B.Fab")
		)
		(fp_line
			(start -0.120396 0.3048)
			(end -0.120396 0.2794)
			(stroke
				(width 0.1)
				(type default)
			)
			(layer "B.Fab")
		)
		(fp_line
			(start 0.12065 -0.305054)
			(end 0.12065 -0.2794)
			(stroke
				(width 0.1)
				(type default)
			)
			(layer "B.Fab")
		)
		(fp_line
			(start 0.12065 -0.2794)
			(end -0.12065 -0.2794)
			(stroke
				(width 0.1)
				(type default)
			)
			(layer "B.Fab")
		)
		(fp_line
			(start 0.12065 0.2794)
			(end 0.12065 0.3048)
			(stroke
				(width 0.1)
				(type default)
			)
			(layer "B.Fab")
		)
		(fp_line
			(start 0.12065 0.3048)
			(end 0.67945 0.3048)
			(stroke
				(width 0.1)
				(type default)
			)
			(layer "B.Fab")
		)
		(fp_line
			(start 0.67945 -0.305054)
			(end 0.12065 -0.305054)
			(stroke
				(width 0.1)
				(type default)
			)
			(layer "B.Fab")
		)
		(fp_line
			(start 0.67945 0.3048)
			(end 0.67945 -0.305054)
			(stroke
				(width 0.1)
				(type default)
			)
			(layer "B.Fab")
		)
		(pad "1" smd circle
			(at 0.40005 0 180)
			(size 0 0)
			(layers "B.Cu" "B.Mask" "B.Paste")
			(net "PWRGD_NIC1_PWR_GOOD")
		)
		(pad "2" smd circle
			(at -0.40005 0 180)
			(size 0 0)
			(layers "B.Cu" "B.Mask" "B.Paste")
			(net "PWRGD_NIC1_PWR_GOOD_R")
		)
	)
	(footprint ""
		(layer "B.Cu")
		(at 75.72375 -291.624766 90)
		(property "Reference" "R984"
			(at 0 0 90)
			(layer "B.SilkS")
			(hide yes)
			(effects
				(font
					(size 1.27 1.27)
				)
				(justify mirror)
			)
		)
		(property "Value" ""
			(at 0 0 90)
			(layer "B.Fab")
			(effects
				(font
					(size 1.27 1.27)
				)
				(justify mirror)
			)
		)
		(duplicate_pad_numbers_are_jumpers no)
		(fp_line
			(start 0.7874 -0.4064)
			(end -0.7874 -0.4064)
			(stroke
				(width 0.1524)
				(type default)
			)
			(layer "B.SilkS")
		)
		(fp_line
			(start -0.7874 -0.4064)
			(end -0.7874 0.4064)
			(stroke
				(width 0.1524)
				(type default)
			)
			(layer "B.SilkS")
		)
		(fp_line
			(start 0.7874 0.4064)
			(end 0.7874 -0.4064)
			(stroke
				(width 0.1524)
				(type default)
			)
			(layer "B.SilkS")
		)
		(fp_line
			(start -0.7874 0.4064)
			(end 0.7874 0.4064)
			(stroke
				(width 0.1524)
				(type default)
			)
			(layer "B.SilkS")
		)
		(fp_line
			(start 0.67945 -0.305054)
			(end 0.12065 -0.305054)
			(stroke
				(width 0.1)
				(type default)
			)
			(layer "B.Fab")
		)
		(fp_line
			(start 0.12065 -0.305054)
			(end 0.12065 -0.2794)
			(stroke
				(width 0.1)
				(type default)
			)
			(layer "B.Fab")
		)
		(fp_line
			(start -0.12065 -0.3048)
			(end -0.67945 -0.3048)
			(stroke
				(width 0.1)
				(type default)
			)
			(layer "B.Fab")
		)
		(fp_line
			(start -0.67945 -0.3048)
			(end -0.67945 0.3048)
			(stroke
				(width 0.1)
				(type default)
			)
			(layer "B.Fab")
		)
		(fp_line
			(start 0.12065 -0.2794)
			(end -0.12065 -0.2794)
			(stroke
				(width 0.1)
				(type default)
			)
			(layer "B.Fab")
		)
		(fp_line
			(start -0.12065 -0.2794)
			(end -0.12065 -0.3048)
			(stroke
				(width 0.1)
				(type default)
			)
			(layer "B.Fab")
		)
		(fp_line
			(start 0.12065 0.2794)
			(end 0.12065 0.3048)
			(stroke
				(width 0.1)
				(type default)
			)
			(layer "B.Fab")
		)
		(fp_line
			(start -0.120396 0.2794)
			(end 0.12065 0.2794)
			(stroke
				(width 0.1)
				(type default)
			)
			(layer "B.Fab")
		)
		(fp_line
			(start 0.67945 0.3048)
			(end 0.67945 -0.305054)
			(stroke
				(width 0.1)
				(type default)
			)
			(layer "B.Fab")
		)
		(fp_line
			(start 0.12065 0.3048)
			(end 0.67945 0.3048)
			(stroke
				(width 0.1)
				(type default)
			)
			(layer "B.Fab")
		)
		(fp_line
			(start -0.120396 0.3048)
			(end -0.120396 0.2794)
			(stroke
				(width 0.1)
				(type default)
			)
			(layer "B.Fab")
		)
		(fp_line
			(start -0.67945 0.3048)
			(end -0.120396 0.3048)
			(stroke
				(width 0.1)
				(type default)
			)
			(layer "B.Fab")
		)
		(pad "1" smd circle
			(at 0.40005 0 270)
			(size 0 0)
			(layers "B.Cu" "B.Mask" "B.Paste")
			(net "UART_PEX0_CLI_TX")
		)
		(pad "2" smd circle
			(at -0.40005 0 270)
			(size 0 0)
			(layers "B.Cu" "B.Mask" "B.Paste")
			(net "UART_PEX0_CLI_R_TX")
		)
	)
	(footprint ""
		(layer "B.Cu")
		(at 171.020232 -296.37482)
		(property "Reference" "C1366"
			(at 0 0 0)
			(layer "B.SilkS")
			(hide yes)
			(effects
				(font
					(size 1.27 1.27)
				)
				(justify mirror)
			)
		)
		(property "Value" ""
			(at 0 0 0)
			(layer "B.Fab")
			(effects
				(font
					(size 1.27 1.27)
				)
				(justify mirror)
			)
		)
		(duplicate_pad_numbers_are_jumpers no)
		(fp_line
			(start -0.299974 -0.150114)
			(end -0.299974 0.150114)
			(stroke
				(width 0.1)
				(type default)
			)
			(layer "B.Fab")
		)
		(fp_line
			(start -0.299974 0.150114)
			(end 0.299974 0.150114)
			(stroke
				(width 0.1)
				(type default)
			)
			(layer "B.Fab")
		)
		(fp_line
			(start 0.299974 -0.150114)
			(end -0.299974 -0.150114)
			(stroke
				(width 0.1)
				(type default)
			)
			(layer "B.Fab")
		)
		(fp_line
			(start 0.299974 0.150114)
			(end 0.299974 -0.150114)
			(stroke
				(width 0.1)
				(type default)
			)
			(layer "B.Fab")
		)
		(pad "1" smd rect
			(at 0.2667 0 180)
			(size 0.3048 0.381)
			(layers "B.Cu" "B.Mask" "B.Paste")
			(net "P0V8_PEX1")
		)
		(pad "2" smd rect
			(at -0.2667 0 180)
			(size 0.3048 0.381)
			(layers "B.Cu" "B.Mask" "B.Paste")
			(net "GND")
		)
	)
	(footprint ""
		(layer "B.Cu")
		(at 60.158376 -286.399732 90)
		(property "Reference" "C2959"
			(at 0 0 90)
			(layer "B.SilkS")
			(hide yes)
			(effects
				(font
					(size 1.27 1.27)
				)
				(justify mirror)
			)
		)
		(property "Value" ""
			(at 0 0 90)
			(layer "B.Fab")
			(effects
				(font
					(size 1.27 1.27)
				)
				(justify mirror)
			)
		)
		(duplicate_pad_numbers_are_jumpers no)
		(fp_line
			(start 0.299974 -0.150114)
			(end -0.299974 -0.150114)
			(stroke
				(width 0.1)
				(type default)
			)
			(layer "B.Fab")
		)
		(fp_line
			(start -0.299974 -0.150114)
			(end -0.299974 0.150114)
			(stroke
				(width 0.1)
				(type default)
			)
			(layer "B.Fab")
		)
		(fp_line
			(start 0.299974 0.150114)
			(end 0.299974 -0.150114)
			(stroke
				(width 0.1)
				(type default)
			)
			(layer "B.Fab")
		)
		(fp_line
			(start -0.299974 0.150114)
			(end 0.299974 0.150114)
			(stroke
				(width 0.1)
				(type default)
			)
			(layer "B.Fab")
		)
		(pad "1" smd rect
			(at 0.2667 0 270)
			(size 0.3048 0.381)
			(layers "B.Cu" "B.Mask" "B.Paste")
			(net "P1V25_SERDES_VDDPLL_PEX0")
		)
		(pad "2" smd rect
			(at -0.2667 0 270)
			(size 0.3048 0.381)
			(layers "B.Cu" "B.Mask" "B.Paste")
			(net "GND")
		)
	)
	(footprint ""
		(layer "B.Cu")
		(at 171.949872 -288.299906 90)
		(property "Reference" "C3101"
			(at 0 0 90)
			(layer "B.SilkS")
			(hide yes)
			(effects
				(font
					(size 1.27 1.27)
				)
				(justify mirror)
			)
		)
		(property "Value" ""
			(at 0 0 90)
			(layer "B.Fab")
			(effects
				(font
					(size 1.27 1.27)
				)
				(justify mirror)
			)
		)
		(duplicate_pad_numbers_are_jumpers no)
		(fp_line
			(start 0.299974 -0.150114)
			(end -0.299974 -0.150114)
			(stroke
				(width 0.1)
				(type default)
			)
			(layer "B.Fab")
		)
		(fp_line
			(start -0.299974 -0.150114)
			(end -0.299974 0.150114)
			(stroke
				(width 0.1)
				(type default)
			)
			(layer "B.Fab")
		)
		(fp_line
			(start 0.299974 0.150114)
			(end 0.299974 -0.150114)
			(stroke
				(width 0.1)
				(type default)
			)
			(layer "B.Fab")
		)
		(fp_line
			(start -0.299974 0.150114)
			(end 0.299974 0.150114)
			(stroke
				(width 0.1)
				(type default)
			)
			(layer "B.Fab")
		)
		(pad "1" smd rect
			(at 0.2667 0 270)
			(size 0.3048 0.381)
			(layers "B.Cu" "B.Mask" "B.Paste")
			(net "P1V25_PEX1")
		)
		(pad "2" smd rect
			(at -0.2667 0 270)
			(size 0.3048 0.381)
			(layers "B.Cu" "B.Mask" "B.Paste")
			(net "GND")
		)
	)
	(footprint ""
		(layer "B.Cu")
		(at 409.849828 -292.099746 90)
		(property "Reference" "C1963"
			(at 0 0 90)
			(layer "B.SilkS")
			(hide yes)
			(effects
				(font
					(size 1.27 1.27)
				)
				(justify mirror)
			)
		)
		(property "Value" ""
			(at 0 0 90)
			(layer "B.Fab")
			(effects
				(font
					(size 1.27 1.27)
				)
				(justify mirror)
			)
		)
		(duplicate_pad_numbers_are_jumpers no)
		(fp_line
			(start 0.299974 -0.150114)
			(end -0.299974 -0.150114)
			(stroke
				(width 0.1)
				(type default)
			)
			(layer "B.Fab")
		)
		(fp_line
			(start -0.299974 -0.150114)
			(end -0.299974 0.150114)
			(stroke
				(width 0.1)
				(type default)
			)
			(layer "B.Fab")
		)
		(fp_line
			(start 0.299974 0.150114)
			(end 0.299974 -0.150114)
			(stroke
				(width 0.1)
				(type default)
			)
			(layer "B.Fab")
		)
		(fp_line
			(start -0.299974 0.150114)
			(end 0.299974 0.150114)
			(stroke
				(width 0.1)
				(type default)
			)
			(layer "B.Fab")
		)
		(pad "1" smd rect
			(at 0.2667 0 270)
			(size 0.3048 0.381)
			(layers "B.Cu" "B.Mask" "B.Paste")
			(net "P0V8_SERDES_VDDA_PEX3")
		)
		(pad "2" smd rect
			(at -0.2667 0 270)
			(size 0.3048 0.381)
			(layers "B.Cu" "B.Mask" "B.Paste")
			(net "GND")
		)
	)
	(footprint ""
		(layer "B.Cu")
		(at 203.217018 -244.609112 90)
		(property "Reference" "C4007"
			(at 0 0 90)
			(layer "B.SilkS")
			(hide yes)
			(effects
				(font
					(size 1.27 1.27)
				)
				(justify mirror)
			)
		)
		(property "Value" ""
			(at 0 0 90)
			(layer "B.Fab")
			(effects
				(font
					(size 1.27 1.27)
				)
				(justify mirror)
			)
		)
		(duplicate_pad_numbers_are_jumpers no)
		(fp_line
			(start 0.7874 -0.4064)
			(end -0.7874 -0.4064)
			(stroke
				(width 0.1524)
				(type default)
			)
			(layer "B.SilkS")
		)
		(fp_line
			(start -0.7874 -0.4064)
			(end -0.7874 0.4064)
			(stroke
				(width 0.1524)
				(type default)
			)
			(layer "B.SilkS")
		)
		(fp_line
			(start 0.7874 0.4064)
			(end 0.7874 -0.4064)
			(stroke
				(width 0.1524)
				(type default)
			)
			(layer "B.SilkS")
		)
		(fp_line
			(start -0.7874 0.4064)
			(end 0.7874 0.4064)
			(stroke
				(width 0.1524)
				(type default)
			)
			(layer "B.SilkS")
		)
		(fp_line
			(start 0.67945 -0.305054)
			(end 0.12065 -0.305054)
			(stroke
				(width 0.1)
				(type default)
			)
			(layer "B.Fab")
		)
		(fp_line
			(start 0.12065 -0.305054)
			(end 0.12065 -0.2794)
			(stroke
				(width 0.1)
				(type default)
			)
			(layer "B.Fab")
		)
		(fp_line
			(start -0.12065 -0.3048)
			(end -0.67945 -0.3048)
			(stroke
				(width 0.1)
				(type default)
			)
			(layer "B.Fab")
		)
		(fp_line
			(start -0.67945 -0.3048)
			(end -0.67945 0.3048)
			(stroke
				(width 0.1)
				(type default)
			)
			(layer "B.Fab")
		)
		(fp_line
			(start 0.12065 -0.2794)
			(end -0.12065 -0.2794)
			(stroke
				(width 0.1)
				(type default)
			)
			(layer "B.Fab")
		)
		(fp_line
			(start -0.12065 -0.2794)
			(end -0.12065 -0.3048)
			(stroke
				(width 0.1)
				(type default)
			)
			(layer "B.Fab")
		)
		(fp_line
			(start 0.12065 0.2794)
			(end 0.12065 0.3048)
			(stroke
				(width 0.1)
				(type default)
			)
			(layer "B.Fab")
		)
		(fp_line
			(start -0.120396 0.2794)
			(end 0.12065 0.2794)
			(stroke
				(width 0.1)
				(type default)
			)
			(layer "B.Fab")
		)
		(fp_line
			(start 0.67945 0.3048)
			(end 0.67945 -0.305054)
			(stroke
				(width 0.1)
				(type default)
			)
			(layer "B.Fab")
		)
		(fp_line
			(start 0.12065 0.3048)
			(end 0.67945 0.3048)
			(stroke
				(width 0.1)
				(type default)
			)
			(layer "B.Fab")
		)
		(fp_line
			(start -0.120396 0.3048)
			(end -0.120396 0.2794)
			(stroke
				(width 0.1)
				(type default)
			)
			(layer "B.Fab")
		)
		(fp_line
			(start -0.67945 0.3048)
			(end -0.120396 0.3048)
			(stroke
				(width 0.1)
				(type default)
			)
			(layer "B.Fab")
		)
		(pad "1" smd circle
			(at 0.40005 0 270)
			(size 0 0)
			(layers "B.Cu" "B.Mask" "B.Paste")
			(net "P1V8_PEX")
		)
		(pad "2" smd circle
			(at -0.40005 0 270)
			(size 0 0)
			(layers "B.Cu" "B.Mask" "B.Paste")
			(net "GND")
		)
	)
	(footprint ""
		(layer "B.Cu")
		(at 410.799788 -290.199826 90)
		(property "Reference" "C1965"
			(at 0 0 90)
			(layer "B.SilkS")
			(hide yes)
			(effects
				(font
					(size 1.27 1.27)
				)
				(justify mirror)
			)
		)
		(property "Value" ""
			(at 0 0 90)
			(layer "B.Fab")
			(effects
				(font
					(size 1.27 1.27)
				)
				(justify mirror)
			)
		)
		(duplicate_pad_numbers_are_jumpers no)
		(fp_line
			(start 0.299974 -0.150114)
			(end -0.299974 -0.150114)
			(stroke
				(width 0.1)
				(type default)
			)
			(layer "B.Fab")
		)
		(fp_line
			(start -0.299974 -0.150114)
			(end -0.299974 0.150114)
			(stroke
				(width 0.1)
				(type default)
			)
			(layer "B.Fab")
		)
		(fp_line
			(start 0.299974 0.150114)
			(end 0.299974 -0.150114)
			(stroke
				(width 0.1)
				(type default)
			)
			(layer "B.Fab")
		)
		(fp_line
			(start -0.299974 0.150114)
			(end 0.299974 0.150114)
			(stroke
				(width 0.1)
				(type default)
			)
			(layer "B.Fab")
		)
		(pad "1" smd rect
			(at 0.2667 0 270)
			(size 0.3048 0.381)
			(layers "B.Cu" "B.Mask" "B.Paste")
			(net "P0V8_SERDES_VDDA_PEX3")
		)
		(pad "2" smd rect
			(at -0.2667 0 270)
			(size 0.3048 0.381)
			(layers "B.Cu" "B.Mask" "B.Paste")
			(net "GND")
		)
	)
)
